#ISCELL
  mstr_misc dns *
  *
#ISCELL
  mstr_symbols cad_note *
  *
#ISCELL
  mstr_symbols design_note *
  *
#ISCELL
  mstr_symbols intel_corp_bpage *
  *
#CELL
  mstr_discrete cap *
  page239_i12
#CELL
  mstr_discrete res *
  page239_i15
#ISCELL
  mstr_symbols gnd *
  page239_i16
#CELL
  mstr_discrete cap *
  page239_i22
#CELL
  mstr_discrete cap *
  page239_i30
#ISCELL
  mstr_standard offpage *
  page239_i33
#ISCELL
  mstr_symbols p3v3_stby *
  page239_i35
#ISCELL
  mstr_symbols gnd *
  page239_i38
#ISCELL
  mstr_symbols gnd *
  page239_i39
#CELL
  mstr_discrete cap *
  page239_i4
#ISCELL
  mstr_standard offpage *
  page239_i42
#ISCELL
  mstr_symbols gnd *
  page239_i5
#CELL
  mstr_discrete res *
  page239_i6
#ISCELL
  mstr_symbols gnd *
  page239_i62
#ISCELL
  mstr_symbols p3v3_stby *
  page239_i67
#ISCELL
  mstr_symbols gnd *
  page239_i69
#CELL
  mstr_discrete cap *
  page239_i7
#CELL
  mstr_vreg rt9059 *
  page239_i70
#CELL
  dev_discrete cap_a *
  page239_i71
#CELL
  mstr_discrete res *
  page239_i72
#CELL
  mstr_vreg rt9059 *
  page239_i73
#ISCELL
  mstr_symbols gnd *
  page239_i74
#ISCELL
  mstr_symbols p3v3_stby *
  page239_i75
#ISCELL
  mstr_standard offpage *
  page239_i76
#CELL
  mstr_discrete res *
  page239_i77
#ISCELL
  mstr_symbols p3v3_stby *
  page239_i78
#CELL
  mstr_discrete res *
  page239_i79
#CELL
  mstr_discrete cap *
  page239_i81
#ISCELL
  mstr_symbols gnd *
  page239_i82
#CELL
  mstr_discrete cap *
  page239_i83
#CELL
  mstr_discrete cap *
  page239_i84
#ISCELL
  mstr_symbols gnd *
  page239_i85
#CELL
  mstr_discrete res *
  page239_i87
#ISCELL
  mstr_symbols gnd *
  page239_i88
#ISCELL
  mstr_symbols gnd *
  page239_i89
#ISCELL
  mstr_symbols gnd *
  page239_i9
#CELL
  dev_discrete cap_a *
  page239_i90
#CELL
  mstr_discrete cap *
  page239_i91
#CELL
  mstr_discrete cap *
  page239_i92
#ISCELL
  mstr_symbols gnd *
  page239_i93
#ISCELL
  mstr_standard offpage *
  page239_i94
#ISCELL
  mstr_symbols gnd *
  page239_i95
#ISCELL
  w_power w_vcc_circle *
  page239_i96
#ISCELL
  w_power w_vcc_circle *
  page239_i97
#CELL
  w_hdl 5k1r2f-2-gp *
  page239_i98
#CELL
  w_hdl 21k5r2f-gp *
  page239_i99
